(kicad_pcb
	(version 20260206)
	(generator "pcbnew")
	(generator_version "10.0")
	(general
		(thickness 1.6)
		(legacy_teardrops no)
	)
	(paper "A4")
	(title_block
		(title "04192023_DAF0TMB3IC0_F0TG_MB_C_brd_V02_OCP.brd")
		(comment 1 "Grand Teton / footprints 5224-5230 of 8354")
	)
	(layers
		(0 "F.Cu" signal "TOP")
		(4 "In1.Cu" signal "GND")
		(6 "In2.Cu" signal "IN1")
		(8 "In3.Cu" signal "GND1")
		(10 "In4.Cu" signal "IN2")
		(12 "In5.Cu" signal "GND2")
		(14 "In6.Cu" signal "IN3")
		(16 "In7.Cu" signal "GND3")
		(18 "In8.Cu" signal "VCC")
		(20 "In9.Cu" signal "VCC1")
		(22 "In10.Cu" signal "GND4")
		(24 "In11.Cu" signal "IN4")
		(26 "In12.Cu" signal "GND5")
		(28 "In13.Cu" signal "IN5")
		(30 "In14.Cu" signal "GND6")
		(32 "In15.Cu" signal "IN6")
		(34 "In16.Cu" signal "GND7")
		(2 "B.Cu" signal "BOTTOM")
		(9 "F.Adhes" user "F.Adhesive")
		(11 "B.Adhes" user "B.Adhesive")
		(13 "F.Paste" user "Package Geometry/Pastemask Top")
		(15 "B.Paste" user "Package Geometry/Pastemask Bottom")
		(5 "F.SilkS" user "Ref Des/Silkscreen Top")
		(7 "B.SilkS" user "Ref Des/Silkscreen Bottom")
		(1 "F.Mask" user "Board Geometry/Soldermask Top")
		(3 "B.Mask" user "Board Geometry/Soldermask Bottom")
		(17 "Dwgs.User" user "User.Drawings")
		(19 "Cmts.User" user "User.Comments")
		(21 "Eco1.User" user "User.Eco1")
		(23 "Eco2.User" user "User.Eco2")
		(25 "Edge.Cuts" user "Board Geometry/Outline")
		(27 "Margin" user)
		(31 "F.CrtYd" user "Package Geometry/Place Bound Top")
		(29 "B.CrtYd" user "Package Geometry/Place Bound Bottom")
		(35 "F.Fab" user "Ref Des/Assembly Top")
		(33 "B.Fab" user "Ref Des/Assembly Bottom")
	)
	(footprint ""
		(layer "B.Cu")
		(at 291.52469 -195.859146 180)
		(property "Reference" "R1677"
			(at 0 0 0)
			(layer "B.SilkS")
			(hide yes)
			(effects
				(font
					(size 1.27 1.27)
				)
				(justify mirror)
			)
		)
		(property "Value" ""
			(at 0 0 0)
			(layer "B.Fab")
			(effects
				(font
					(size 1.27 1.27)
				)
				(justify mirror)
			)
		)
		(duplicate_pad_numbers_are_jumpers no)
		(fp_line
			(start 0.7874 0.4064)
			(end 0.7874 -0.4064)
			(stroke
				(width 0.1524)
				(type default)
			)
			(layer "B.SilkS")
		)
		(fp_line
			(start 0.7874 -0.4064)
			(end -0.7874 -0.4064)
			(stroke
				(width 0.1524)
				(type default)
			)
			(layer "B.SilkS")
		)
		(fp_line
			(start -0.7874 0.4064)
			(end 0.7874 0.4064)
			(stroke
				(width 0.1524)
				(type default)
			)
			(layer "B.SilkS")
		)
		(fp_line
			(start -0.7874 -0.4064)
			(end -0.7874 0.4064)
			(stroke
				(width 0.1524)
				(type default)
			)
			(layer "B.SilkS")
		)
		(fp_line
			(start 0.67945 0.3048)
			(end 0.67945 -0.305054)
			(stroke
				(width 0.1)
				(type default)
			)
			(layer "B.Fab")
		)
		(fp_line
			(start 0.67945 -0.305054)
			(end 0.12065 -0.305054)
			(stroke
				(width 0.1)
				(type default)
			)
			(layer "B.Fab")
		)
		(fp_line
			(start 0.12065 0.3048)
			(end 0.67945 0.3048)
			(stroke
				(width 0.1)
				(type default)
			)
			(layer "B.Fab")
		)
		(fp_line
			(start 0.12065 0.2794)
			(end 0.12065 0.3048)
			(stroke
				(width 0.1)
				(type default)
			)
			(layer "B.Fab")
		)
		(fp_line
			(start 0.12065 -0.2794)
			(end -0.12065 -0.2794)
			(stroke
				(width 0.1)
				(type default)
			)
			(layer "B.Fab")
		)
		(fp_line
			(start 0.12065 -0.305054)
			(end 0.12065 -0.2794)
			(stroke
				(width 0.1)
				(type default)
			)
			(layer "B.Fab")
		)
		(fp_line
			(start -0.120396 0.3048)
			(end -0.120396 0.2794)
			(stroke
				(width 0.1)
				(type default)
			)
			(layer "B.Fab")
		)
		(fp_line
			(start -0.120396 0.2794)
			(end 0.12065 0.2794)
			(stroke
				(width 0.1)
				(type default)
			)
			(layer "B.Fab")
		)
		(fp_line
			(start -0.12065 -0.2794)
			(end -0.12065 -0.3048)
			(stroke
				(width 0.1)
				(type default)
			)
			(layer "B.Fab")
		)
		(fp_line
			(start -0.12065 -0.3048)
			(end -0.67945 -0.3048)
			(stroke
				(width 0.1)
				(type default)
			)
			(layer "B.Fab")
		)
		(fp_line
			(start -0.67945 0.3048)
			(end -0.120396 0.3048)
			(stroke
				(width 0.1)
				(type default)
			)
			(layer "B.Fab")
		)
		(fp_line
			(start -0.67945 -0.3048)
			(end -0.67945 0.3048)
			(stroke
				(width 0.1)
				(type default)
			)
			(layer "B.Fab")
		)
		(pad "1" smd circle
			(at 0.40005 0)
			(size 0 0)
			(layers "B.Cu" "B.Mask" "B.Paste")
			(net "I3C_SPD_DDRAF_CPU0_SDA")
		)
		(pad "2" smd circle
			(at -0.40005 0)
			(size 0 0)
			(layers "B.Cu" "B.Mask" "B.Paste")
			(net "I3C_SPD_DDRC_CPU0_SDA")
		)
	)
	(footprint ""
		(layer "B.Cu")
		(at 380.282958 -205.101952 -90)
		(property "Reference" "R428"
			(at 0 0 90)
			(layer "B.SilkS")
			(hide yes)
			(effects
				(font
					(size 1.27 1.27)
				)
				(justify mirror)
			)
		)
		(property "Value" ""
			(at 0 0 90)
			(layer "B.Fab")
			(effects
				(font
					(size 1.27 1.27)
				)
				(justify mirror)
			)
		)
		(duplicate_pad_numbers_are_jumpers no)
		(fp_line
			(start -0.7874 0.4064)
			(end 0.7874 0.4064)
			(stroke
				(width 0.1524)
				(type default)
			)
			(layer "B.SilkS")
		)
		(fp_line
			(start 0.7874 0.4064)
			(end 0.7874 -0.4064)
			(stroke
				(width 0.1524)
				(type default)
			)
			(layer "B.SilkS")
		)
		(fp_line
			(start -0.7874 -0.4064)
			(end -0.7874 0.4064)
			(stroke
				(width 0.1524)
				(type default)
			)
			(layer "B.SilkS")
		)
		(fp_line
			(start 0.7874 -0.4064)
			(end -0.7874 -0.4064)
			(stroke
				(width 0.1524)
				(type default)
			)
			(layer "B.SilkS")
		)
		(fp_line
			(start -0.67945 0.3048)
			(end -0.120396 0.3048)
			(stroke
				(width 0.1)
				(type default)
			)
			(layer "B.Fab")
		)
		(fp_line
			(start -0.120396 0.3048)
			(end -0.120396 0.2794)
			(stroke
				(width 0.1)
				(type default)
			)
			(layer "B.Fab")
		)
		(fp_line
			(start 0.12065 0.3048)
			(end 0.67945 0.3048)
			(stroke
				(width 0.1)
				(type default)
			)
			(layer "B.Fab")
		)
		(fp_line
			(start 0.67945 0.3048)
			(end 0.67945 -0.305054)
			(stroke
				(width 0.1)
				(type default)
			)
			(layer "B.Fab")
		)
		(fp_line
			(start -0.120396 0.2794)
			(end 0.12065 0.2794)
			(stroke
				(width 0.1)
				(type default)
			)
			(layer "B.Fab")
		)
		(fp_line
			(start 0.12065 0.2794)
			(end 0.12065 0.3048)
			(stroke
				(width 0.1)
				(type default)
			)
			(layer "B.Fab")
		)
		(fp_line
			(start -0.12065 -0.2794)
			(end -0.12065 -0.3048)
			(stroke
				(width 0.1)
				(type default)
			)
			(layer "B.Fab")
		)
		(fp_line
			(start 0.12065 -0.2794)
			(end -0.12065 -0.2794)
			(stroke
				(width 0.1)
				(type default)
			)
			(layer "B.Fab")
		)
		(fp_line
			(start -0.67945 -0.3048)
			(end -0.67945 0.3048)
			(stroke
				(width 0.1)
				(type default)
			)
			(layer "B.Fab")
		)
		(fp_line
			(start -0.12065 -0.3048)
			(end -0.67945 -0.3048)
			(stroke
				(width 0.1)
				(type default)
			)
			(layer "B.Fab")
		)
		(fp_line
			(start 0.12065 -0.305054)
			(end 0.12065 -0.2794)
			(stroke
				(width 0.1)
				(type default)
			)
			(layer "B.Fab")
		)
		(fp_line
			(start 0.67945 -0.305054)
			(end 0.12065 -0.305054)
			(stroke
				(width 0.1)
				(type default)
			)
			(layer "B.Fab")
		)
		(pad "1" smd rect
			(at 0.40005 0 270)
			(size 0.4572 0.508)
			(layers "B.Cu" "B.Mask" "B.Paste")
			(net "I3C_1_SPD_DDRGL_CPU0_SCL")
		)
		(pad "2" smd rect
			(at -0.40005 0 270)
			(size 0.4572 0.508)
			(layers "B.Cu" "B.Mask" "B.Paste")
			(net "I3C_1_SPD_DDRGL_CPU0_R_SCL")
		)
	)
	(footprint ""
		(layer "B.Cu")
		(at 12.060428 -135.63219 180)
		(property "Reference" "C2257"
			(at 0 0 0)
			(layer "B.SilkS")
			(hide yes)
			(effects
				(font
					(size 1.27 1.27)
				)
				(justify mirror)
			)
		)
		(property "Value" ""
			(at 0 0 0)
			(layer "B.Fab")
			(effects
				(font
					(size 1.27 1.27)
				)
				(justify mirror)
			)
		)
		(duplicate_pad_numbers_are_jumpers no)
		(fp_line
			(start 0.7874 0.4064)
			(end 0.7874 -0.4064)
			(stroke
				(width 0.1524)
				(type default)
			)
			(layer "B.SilkS")
		)
		(fp_line
			(start 0.7874 -0.4064)
			(end -0.7874 -0.4064)
			(stroke
				(width 0.1524)
				(type default)
			)
			(layer "B.SilkS")
		)
		(fp_line
			(start -0.7874 0.4064)
			(end 0.7874 0.4064)
			(stroke
				(width 0.1524)
				(type default)
			)
			(layer "B.SilkS")
		)
		(fp_line
			(start -0.7874 -0.4064)
			(end -0.7874 0.4064)
			(stroke
				(width 0.1524)
				(type default)
			)
			(layer "B.SilkS")
		)
		(fp_line
			(start 0.67945 0.3048)
			(end 0.67945 -0.305054)
			(stroke
				(width 0.1)
				(type default)
			)
			(layer "B.Fab")
		)
		(fp_line
			(start 0.67945 -0.305054)
			(end 0.12065 -0.305054)
			(stroke
				(width 0.1)
				(type default)
			)
			(layer "B.Fab")
		)
		(fp_line
			(start 0.12065 0.3048)
			(end 0.67945 0.3048)
			(stroke
				(width 0.1)
				(type default)
			)
			(layer "B.Fab")
		)
		(fp_line
			(start 0.12065 0.2794)
			(end 0.12065 0.3048)
			(stroke
				(width 0.1)
				(type default)
			)
			(layer "B.Fab")
		)
		(fp_line
			(start 0.12065 -0.2794)
			(end -0.12065 -0.2794)
			(stroke
				(width 0.1)
				(type default)
			)
			(layer "B.Fab")
		)
		(fp_line
			(start 0.12065 -0.305054)
			(end 0.12065 -0.2794)
			(stroke
				(width 0.1)
				(type default)
			)
			(layer "B.Fab")
		)
		(fp_line
			(start -0.120396 0.3048)
			(end -0.120396 0.2794)
			(stroke
				(width 0.1)
				(type default)
			)
			(layer "B.Fab")
		)
		(fp_line
			(start -0.120396 0.2794)
			(end 0.12065 0.2794)
			(stroke
				(width 0.1)
				(type default)
			)
			(layer "B.Fab")
		)
		(fp_line
			(start -0.12065 -0.2794)
			(end -0.12065 -0.3048)
			(stroke
				(width 0.1)
				(type default)
			)
			(layer "B.Fab")
		)
		(fp_line
			(start -0.12065 -0.3048)
			(end -0.67945 -0.3048)
			(stroke
				(width 0.1)
				(type default)
			)
			(layer "B.Fab")
		)
		(fp_line
			(start -0.67945 0.3048)
			(end -0.120396 0.3048)
			(stroke
				(width 0.1)
				(type default)
			)
			(layer "B.Fab")
		)
		(fp_line
			(start -0.67945 -0.3048)
			(end -0.67945 0.3048)
			(stroke
				(width 0.1)
				(type default)
			)
			(layer "B.Fab")
		)
		(pad "1" smd circle
			(at 0.40005 0)
			(size 0 0)
			(layers "B.Cu" "B.Mask" "B.Paste")
			(net "VFG3P3_CLK_GEN")
		)
		(pad "2" smd circle
			(at -0.40005 0)
			(size 0 0)
			(layers "B.Cu" "B.Mask" "B.Paste")
			(net "GND")
		)
	)
	(footprint ""
		(layer "B.Cu")
		(at 183.36006 -407.222198 -90)
		(property "Reference" "PR3927"
			(at 0 0 90)
			(layer "B.SilkS")
			(hide yes)
			(effects
				(font
					(size 1.27 1.27)
				)
				(justify mirror)
			)
		)
		(property "Value" ""
			(at 0 0 90)
			(layer "B.Fab")
			(effects
				(font
					(size 1.27 1.27)
				)
				(justify mirror)
			)
		)
		(duplicate_pad_numbers_are_jumpers no)
		(fp_line
			(start -0.7874 0.4064)
			(end 0.7874 0.4064)
			(stroke
				(width 0.1524)
				(type default)
			)
			(layer "B.SilkS")
		)
		(fp_line
			(start 0.7874 0.4064)
			(end 0.7874 -0.4064)
			(stroke
				(width 0.1524)
				(type default)
			)
			(layer "B.SilkS")
		)
		(fp_line
			(start -0.7874 -0.4064)
			(end -0.7874 0.4064)
			(stroke
				(width 0.1524)
				(type default)
			)
			(layer "B.SilkS")
		)
		(fp_line
			(start 0.7874 -0.4064)
			(end -0.7874 -0.4064)
			(stroke
				(width 0.1524)
				(type default)
			)
			(layer "B.SilkS")
		)
		(fp_line
			(start -0.67945 0.3048)
			(end -0.120396 0.3048)
			(stroke
				(width 0.1)
				(type default)
			)
			(layer "B.Fab")
		)
		(fp_line
			(start -0.120396 0.3048)
			(end -0.120396 0.2794)
			(stroke
				(width 0.1)
				(type default)
			)
			(layer "B.Fab")
		)
		(fp_line
			(start 0.12065 0.3048)
			(end 0.67945 0.3048)
			(stroke
				(width 0.1)
				(type default)
			)
			(layer "B.Fab")
		)
		(fp_line
			(start 0.67945 0.3048)
			(end 0.67945 -0.305054)
			(stroke
				(width 0.1)
				(type default)
			)
			(layer "B.Fab")
		)
		(fp_line
			(start -0.120396 0.2794)
			(end 0.12065 0.2794)
			(stroke
				(width 0.1)
				(type default)
			)
			(layer "B.Fab")
		)
		(fp_line
			(start 0.12065 0.2794)
			(end 0.12065 0.3048)
			(stroke
				(width 0.1)
				(type default)
			)
			(layer "B.Fab")
		)
		(fp_line
			(start -0.12065 -0.2794)
			(end -0.12065 -0.3048)
			(stroke
				(width 0.1)
				(type default)
			)
			(layer "B.Fab")
		)
		(fp_line
			(start 0.12065 -0.2794)
			(end -0.12065 -0.2794)
			(stroke
				(width 0.1)
				(type default)
			)
			(layer "B.Fab")
		)
		(fp_line
			(start -0.67945 -0.3048)
			(end -0.67945 0.3048)
			(stroke
				(width 0.1)
				(type default)
			)
			(layer "B.Fab")
		)
		(fp_line
			(start -0.12065 -0.3048)
			(end -0.67945 -0.3048)
			(stroke
				(width 0.1)
				(type default)
			)
			(layer "B.Fab")
		)
		(fp_line
			(start 0.12065 -0.305054)
			(end 0.12065 -0.2794)
			(stroke
				(width 0.1)
				(type default)
			)
			(layer "B.Fab")
		)
		(fp_line
			(start 0.67945 -0.305054)
			(end 0.12065 -0.305054)
			(stroke
				(width 0.1)
				(type default)
			)
			(layer "B.Fab")
		)
		(pad "1" smd circle
			(at 0.40005 0 90)
			(size 0 0)
			(layers "B.Cu" "B.Mask" "B.Paste")
			(net "HSC_VSENSE")
		)
		(pad "2" smd circle
			(at -0.40005 0 90)
			(size 0 0)
			(layers "B.Cu" "B.Mask" "B.Paste")
			(net "AGND_HSC")
		)
	)
	(footprint ""
		(layer "B.Cu")
		(at 173.863 -420.243)
		(property "Reference" "C1751"
			(at 0 0 0)
			(layer "B.SilkS")
			(hide yes)
			(effects
				(font
					(size 1.27 1.27)
				)
				(justify mirror)
			)
		)
		(property "Value" ""
			(at 0 0 0)
			(layer "B.Fab")
			(effects
				(font
					(size 1.27 1.27)
				)
				(justify mirror)
			)
		)
		(duplicate_pad_numbers_are_jumpers no)
		(fp_line
			(start -0.7874 -0.4064)
			(end -0.7874 0.4064)
			(stroke
				(width 0.1524)
				(type default)
			)
			(layer "B.SilkS")
		)
		(fp_line
			(start -0.7874 0.4064)
			(end 0.7874 0.4064)
			(stroke
				(width 0.1524)
				(type default)
			)
			(layer "B.SilkS")
		)
		(fp_line
			(start 0.7874 -0.4064)
			(end -0.7874 -0.4064)
			(stroke
				(width 0.1524)
				(type default)
			)
			(layer "B.SilkS")
		)
		(fp_line
			(start 0.7874 0.4064)
			(end 0.7874 -0.4064)
			(stroke
				(width 0.1524)
				(type default)
			)
			(layer "B.SilkS")
		)
		(fp_line
			(start -0.67945 -0.3048)
			(end -0.67945 0.3048)
			(stroke
				(width 0.1)
				(type default)
			)
			(layer "B.Fab")
		)
		(fp_line
			(start -0.67945 0.3048)
			(end -0.120396 0.3048)
			(stroke
				(width 0.1)
				(type default)
			)
			(layer "B.Fab")
		)
		(fp_line
			(start -0.12065 -0.3048)
			(end -0.67945 -0.3048)
			(stroke
				(width 0.1)
				(type default)
			)
			(layer "B.Fab")
		)
		(fp_line
			(start -0.12065 -0.2794)
			(end -0.12065 -0.3048)
			(stroke
				(width 0.1)
				(type default)
			)
			(layer "B.Fab")
		)
		(fp_line
			(start -0.120396 0.2794)
			(end 0.12065 0.2794)
			(stroke
				(width 0.1)
				(type default)
			)
			(layer "B.Fab")
		)
		(fp_line
			(start -0.120396 0.3048)
			(end -0.120396 0.2794)
			(stroke
				(width 0.1)
				(type default)
			)
			(layer "B.Fab")
		)
		(fp_line
			(start 0.12065 -0.305054)
			(end 0.12065 -0.2794)
			(stroke
				(width 0.1)
				(type default)
			)
			(layer "B.Fab")
		)
		(fp_line
			(start 0.12065 -0.2794)
			(end -0.12065 -0.2794)
			(stroke
				(width 0.1)
				(type default)
			)
			(layer "B.Fab")
		)
		(fp_line
			(start 0.12065 0.2794)
			(end 0.12065 0.3048)
			(stroke
				(width 0.1)
				(type default)
			)
			(layer "B.Fab")
		)
		(fp_line
			(start 0.12065 0.3048)
			(end 0.67945 0.3048)
			(stroke
				(width 0.1)
				(type default)
			)
			(layer "B.Fab")
		)
		(fp_line
			(start 0.67945 -0.305054)
			(end 0.12065 -0.305054)
			(stroke
				(width 0.1)
				(type default)
			)
			(layer "B.Fab")
		)
		(fp_line
			(start 0.67945 0.3048)
			(end 0.67945 -0.305054)
			(stroke
				(width 0.1)
				(type default)
			)
			(layer "B.Fab")
		)
		(pad "1" smd circle
			(at 0.40005 0 180)
			(size 0 0)
			(layers "B.Cu" "B.Mask" "B.Paste")
			(net "P3V3_AUX")
		)
		(pad "2" smd circle
			(at -0.40005 0 180)
			(size 0 0)
			(layers "B.Cu" "B.Mask" "B.Paste")
			(net "GND")
		)
	)
	(footprint ""
		(layer "B.Cu")
		(at 419.819074 -398.942052 90)
		(property "Reference" "C977"
			(at 0 0 90)
			(layer "B.SilkS")
			(hide yes)
			(effects
				(font
					(size 1.27 1.27)
				)
				(justify mirror)
			)
		)
		(property "Value" ""
			(at 0 0 90)
			(layer "B.Fab")
			(effects
				(font
					(size 1.27 1.27)
				)
				(justify mirror)
			)
		)
		(duplicate_pad_numbers_are_jumpers no)
		(fp_line
			(start 0.7874 -0.4064)
			(end -0.7874 -0.4064)
			(stroke
				(width 0.1524)
				(type default)
			)
			(layer "B.SilkS")
		)
		(fp_line
			(start -0.7874 -0.4064)
			(end -0.7874 0.4064)
			(stroke
				(width 0.1524)
				(type default)
			)
			(layer "B.SilkS")
		)
		(fp_line
			(start 0.7874 0.4064)
			(end 0.7874 -0.4064)
			(stroke
				(width 0.1524)
				(type default)
			)
			(layer "B.SilkS")
		)
		(fp_line
			(start -0.7874 0.4064)
			(end 0.7874 0.4064)
			(stroke
				(width 0.1524)
				(type default)
			)
			(layer "B.SilkS")
		)
		(fp_line
			(start 0.67945 -0.305054)
			(end 0.12065 -0.305054)
			(stroke
				(width 0.1)
				(type default)
			)
			(layer "B.Fab")
		)
		(fp_line
			(start 0.12065 -0.305054)
			(end 0.12065 -0.2794)
			(stroke
				(width 0.1)
				(type default)
			)
			(layer "B.Fab")
		)
		(fp_line
			(start -0.12065 -0.3048)
			(end -0.67945 -0.3048)
			(stroke
				(width 0.1)
				(type default)
			)
			(layer "B.Fab")
		)
		(fp_line
			(start -0.67945 -0.3048)
			(end -0.67945 0.3048)
			(stroke
				(width 0.1)
				(type default)
			)
			(layer "B.Fab")
		)
		(fp_line
			(start 0.12065 -0.2794)
			(end -0.12065 -0.2794)
			(stroke
				(width 0.1)
				(type default)
			)
			(layer "B.Fab")
		)
		(fp_line
			(start -0.12065 -0.2794)
			(end -0.12065 -0.3048)
			(stroke
				(width 0.1)
				(type default)
			)
			(layer "B.Fab")
		)
		(fp_line
			(start 0.12065 0.2794)
			(end 0.12065 0.3048)
			(stroke
				(width 0.1)
				(type default)
			)
			(layer "B.Fab")
		)
		(fp_line
			(start -0.120396 0.2794)
			(end 0.12065 0.2794)
			(stroke
				(width 0.1)
				(type default)
			)
			(layer "B.Fab")
		)
		(fp_line
			(start 0.67945 0.3048)
			(end 0.67945 -0.305054)
			(stroke
				(width 0.1)
				(type default)
			)
			(layer "B.Fab")
		)
		(fp_line
			(start 0.12065 0.3048)
			(end 0.67945 0.3048)
			(stroke
				(width 0.1)
				(type default)
			)
			(layer "B.Fab")
		)
		(fp_line
			(start -0.120396 0.3048)
			(end -0.120396 0.2794)
			(stroke
				(width 0.1)
				(type default)
			)
			(layer "B.Fab")
		)
		(fp_line
			(start -0.67945 0.3048)
			(end -0.120396 0.3048)
			(stroke
				(width 0.1)
				(type default)
			)
			(layer "B.Fab")
		)
		(pad "1" smd circle
			(at 0.40005 0 270)
			(size 0 0)
			(layers "B.Cu" "B.Mask" "B.Paste")
			(net "P0V9_CPU0_RT2_2A")
		)
		(pad "2" smd circle
			(at -0.40005 0 270)
			(size 0 0)
			(layers "B.Cu" "B.Mask" "B.Paste")
			(net "GND")
		)
	)
	(footprint ""
		(layer "B.Cu")
		(at 397.623538 -393.04468 180)
		(property "Reference" "R1075"
			(at 0 0 0)
			(layer "B.SilkS")
			(hide yes)
			(effects
				(font
					(size 1.27 1.27)
				)
				(justify mirror)
			)
		)
		(property "Value" ""
			(at 0 0 0)
			(layer "B.Fab")
			(effects
				(font
					(size 1.27 1.27)
				)
				(justify mirror)
			)
		)
		(duplicate_pad_numbers_are_jumpers no)
		(fp_line
			(start 0.32512 0.175006)
			(end 0.32512 -0.175006)
			(stroke
				(width 0.1)
				(type default)
			)
			(layer "B.Fab")
		)
		(fp_line
			(start 0.32512 -0.175006)
			(end -0.32512 -0.175006)
			(stroke
				(width 0.1)
				(type default)
			)
			(layer "B.Fab")
		)
		(fp_line
			(start -0.32512 0.175006)
			(end 0.32512 0.175006)
			(stroke
				(width 0.1)
				(type default)
			)
			(layer "B.Fab")
		)
		(fp_line
			(start -0.32512 -0.175006)
			(end -0.32512 0.175006)
			(stroke
				(width 0.1)
				(type default)
			)
			(layer "B.Fab")
		)
		(pad "1" smd rect
			(at 0.2667 0)
			(size 0.3048 0.381)
			(layers "B.Cu" "B.Mask" "B.Paste")
			(net "P1V8_CPU0_RT_1D")
		)
		(pad "2" smd rect
			(at -0.2667 0 180)
			(size 0.3048 0.381)
			(layers "B.Cu" "B.Mask" "B.Paste")
			(net "TEST1_RT_CPU0_P2")
		)
	)
)
